# T6G (Grand Teton) — schematic netlist excerpt (pin names and nets, part order shuffled) for the footprints in the layout excerpt that follows; sources: Cadence DE-HDL packaged netlist, KiCad conversion of 04192023_DAF0TMB3IC0_F0TG_MB_C_brd_V02_OCP.brd

C319  Q_CAP  0.1UF 10V 10% X7S  pkg C0201  page 334 : A = P0V9_CPU1_RT1_2A ; B = GND
C6727  Q_CAP_DIFFBUS  DIFF BUS_0.22UF 6.3V 20% X6S  pkg C0201  page 352 : \1\ = P5E_CPU1_P3_TX_BUF_C_DP<1> ; \2\ = P5E_CPU1_P3_TX_BUF_DP<1>
R6000  Q_RES  0 5% CHIP  pkg 0402LF  page 150 : A = I3C_SCM_0_SCL ; B = I3C_SCM_0_R_SCL
C138  Q_CAP  1UF 4V 20% X6S  pkg 0201  page 323 : A = P0V9_CPU1_RT0_2A ; B = GND

(kicad_pcb
	(version 20260206)
	(generator "pcbnew")
	(generator_version "10.0")
	(general
		(thickness 1.6)
		(legacy_teardrops no)
	)
	(paper "A4")
	(title_block
		(title "04192023_DAF0TMB3IC0_F0TG_MB_C_brd_V02_OCP.brd")
		(comment 1 "Grand Teton / footprints 7989-7992 of 8354")
	)
	(layers
		(0 "F.Cu" signal "TOP")
		(4 "In1.Cu" signal "GND")
		(6 "In2.Cu" signal "IN1")
		(8 "In3.Cu" signal "GND1")
		(10 "In4.Cu" signal "IN2")
		(12 "In5.Cu" signal "GND2")
		(14 "In6.Cu" signal "IN3")
		(16 "In7.Cu" signal "GND3")
		(18 "In8.Cu" signal "VCC")
		(20 "In9.Cu" signal "VCC1")
		(22 "In10.Cu" signal "GND4")
		(24 "In11.Cu" signal "IN4")
		(26 "In12.Cu" signal "GND5")
		(28 "In13.Cu" signal "IN5")
		(30 "In14.Cu" signal "GND6")
		(32 "In15.Cu" signal "IN6")
		(34 "In16.Cu" signal "GND7")
		(2 "B.Cu" signal "BOTTOM")
		(9 "F.Adhes" user "F.Adhesive")
		(11 "B.Adhes" user "B.Adhesive")
		(13 "F.Paste" user "Package Geometry/Pastemask Top")
		(15 "B.Paste" user "Package Geometry/Pastemask Bottom")
		(5 "F.SilkS" user "Ref Des/Silkscreen Top")
		(7 "B.SilkS" user "Ref Des/Silkscreen Bottom")
		(1 "F.Mask" user "Board Geometry/Soldermask Top")
		(3 "B.Mask" user "Board Geometry/Soldermask Bottom")
		(17 "Dwgs.User" user "User.Drawings")
		(19 "Cmts.User" user "User.Comments")
		(21 "Eco1.User" user "User.Eco1")
		(23 "Eco2.User" user "User.Eco2")
		(25 "Edge.Cuts" user "Board Geometry/Outline")
		(27 "Margin" user)
		(31 "F.CrtYd" user "Package Geometry/Place Bound Top")
		(29 "B.CrtYd" user "Package Geometry/Place Bound Bottom")
		(35 "F.Fab" user "Ref Des/Assembly Top")
		(33 "B.Fab" user "Ref Des/Assembly Bottom")
	)
	(footprint ""
		(layer "B.Cu")
		(at 120.377966 -408.517344 90)
		(property "Reference" "C6727"
			(at 0 0 90)
			(layer "B.SilkS")
			(hide yes)
			(effects
				(font
					(size 1.27 1.27)
				)
				(justify mirror)
			)
		)
		(property "Value" ""
			(at 0 0 90)
			(layer "B.Fab")
			(effects
				(font
					(size 1.27 1.27)
				)
				(justify mirror)
			)
		)
		(duplicate_pad_numbers_are_jumpers no)
		(fp_line
			(start 0.299974 -0.150114)
			(end -0.299974 -0.150114)
			(stroke
				(width 0.1)
				(type default)
			)
			(layer "B.Fab")
		)
		(fp_line
			(start -0.299974 -0.150114)
			(end -0.299974 0.150114)
			(stroke
				(width 0.1)
				(type default)
			)
			(layer "B.Fab")
		)
		(fp_line
			(start 0.299974 0.150114)
			(end 0.299974 -0.150114)
			(stroke
				(width 0.1)
				(type default)
			)
			(layer "B.Fab")
		)
		(fp_line
			(start -0.299974 0.150114)
			(end 0.299974 0.150114)
			(stroke
				(width 0.1)
				(type default)
			)
			(layer "B.Fab")
		)
		(pad "1" smd rect
			(at 0.2667 0 270)
			(size 0.3048 0.381)
			(layers "B.Cu" "B.Mask" "B.Paste")
			(net "P5E_CPU1_P3_TX_BUF_C_DP<1>")
		)
		(pad "2" smd rect
			(at -0.2667 0 270)
			(size 0.3048 0.381)
			(layers "B.Cu" "B.Mask" "B.Paste")
			(net "P5E_CPU1_P3_TX_BUF_DP<1>")
		)
	)
	(footprint ""
		(layer "B.Cu")
		(at 190.367412 -13.60043 -90)
		(property "Reference" "R6000"
			(at 0 0 90)
			(layer "B.SilkS")
			(hide yes)
			(effects
				(font
					(size 1.27 1.27)
				)
				(justify mirror)
			)
		)
		(property "Value" ""
			(at 0 0 90)
			(layer "B.Fab")
			(effects
				(font
					(size 1.27 1.27)
				)
				(justify mirror)
			)
		)
		(duplicate_pad_numbers_are_jumpers no)
		(fp_line
			(start -0.7874 0.4064)
			(end 0.7874 0.4064)
			(stroke
				(width 0.1524)
				(type default)
			)
			(layer "B.SilkS")
		)
		(fp_line
			(start 0.7874 0.4064)
			(end 0.7874 -0.4064)
			(stroke
				(width 0.1524)
				(type default)
			)
			(layer "B.SilkS")
		)
		(fp_line
			(start -0.7874 -0.4064)
			(end -0.7874 0.4064)
			(stroke
				(width 0.1524)
				(type default)
			)
			(layer "B.SilkS")
		)
		(fp_line
			(start 0.7874 -0.4064)
			(end -0.7874 -0.4064)
			(stroke
				(width 0.1524)
				(type default)
			)
			(layer "B.SilkS")
		)
		(fp_line
			(start -0.67945 0.3048)
			(end -0.120396 0.3048)
			(stroke
				(width 0.1)
				(type default)
			)
			(layer "B.Fab")
		)
		(fp_line
			(start -0.120396 0.3048)
			(end -0.120396 0.2794)
			(stroke
				(width 0.1)
				(type default)
			)
			(layer "B.Fab")
		)
		(fp_line
			(start 0.12065 0.3048)
			(end 0.67945 0.3048)
			(stroke
				(width 0.1)
				(type default)
			)
			(layer "B.Fab")
		)
		(fp_line
			(start 0.67945 0.3048)
			(end 0.67945 -0.305054)
			(stroke
				(width 0.1)
				(type default)
			)
			(layer "B.Fab")
		)
		(fp_line
			(start -0.120396 0.2794)
			(end 0.12065 0.2794)
			(stroke
				(width 0.1)
				(type default)
			)
			(layer "B.Fab")
		)
		(fp_line
			(start 0.12065 0.2794)
			(end 0.12065 0.3048)
			(stroke
				(width 0.1)
				(type default)
			)
			(layer "B.Fab")
		)
		(fp_line
			(start -0.12065 -0.2794)
			(end -0.12065 -0.3048)
			(stroke
				(width 0.1)
				(type default)
			)
			(layer "B.Fab")
		)
		(fp_line
			(start 0.12065 -0.2794)
			(end -0.12065 -0.2794)
			(stroke
				(width 0.1)
				(type default)
			)
			(layer "B.Fab")
		)
		(fp_line
			(start -0.67945 -0.3048)
			(end -0.67945 0.3048)
			(stroke
				(width 0.1)
				(type default)
			)
			(layer "B.Fab")
		)
		(fp_line
			(start -0.12065 -0.3048)
			(end -0.67945 -0.3048)
			(stroke
				(width 0.1)
				(type default)
			)
			(layer "B.Fab")
		)
		(fp_line
			(start 0.12065 -0.305054)
			(end 0.12065 -0.2794)
			(stroke
				(width 0.1)
				(type default)
			)
			(layer "B.Fab")
		)
		(fp_line
			(start 0.67945 -0.305054)
			(end 0.12065 -0.305054)
			(stroke
				(width 0.1)
				(type default)
			)
			(layer "B.Fab")
		)
		(pad "1" smd circle
			(at 0.40005 0 90)
			(size 0 0)
			(layers "B.Cu" "B.Mask" "B.Paste")
			(net "I3C_SCM_0_SCL")
		)
		(pad "2" smd circle
			(at -0.40005 0 90)
			(size 0 0)
			(layers "B.Cu" "B.Mask" "B.Paste")
			(net "I3C_SCM_0_R_SCL")
		)
	)
	(footprint ""
		(layer "B.Cu")
		(at 49.778666 -386.766562 90)
		(property "Reference" "C138"
			(at 0 0 90)
			(layer "B.SilkS")
			(hide yes)
			(effects
				(font
					(size 1.27 1.27)
				)
				(justify mirror)
			)
		)
		(property "Value" ""
			(at 0 0 90)
			(layer "B.Fab")
			(effects
				(font
					(size 1.27 1.27)
				)
				(justify mirror)
			)
		)
		(duplicate_pad_numbers_are_jumpers no)
		(fp_line
			(start 0.299974 -0.150114)
			(end -0.299974 -0.150114)
			(stroke
				(width 0.1)
				(type default)
			)
			(layer "B.Fab")
		)
		(fp_line
			(start -0.299974 -0.150114)
			(end -0.299974 0.150114)
			(stroke
				(width 0.1)
				(type default)
			)
			(layer "B.Fab")
		)
		(fp_line
			(start 0.299974 0.150114)
			(end 0.299974 -0.150114)
			(stroke
				(width 0.1)
				(type default)
			)
			(layer "B.Fab")
		)
		(fp_line
			(start -0.299974 0.150114)
			(end 0.299974 0.150114)
			(stroke
				(width 0.1)
				(type default)
			)
			(layer "B.Fab")
		)
		(pad "1" smd rect
			(at 0.2667 0 270)
			(size 0.3048 0.381)
			(layers "B.Cu" "B.Mask" "B.Paste")
			(net "P0V9_CPU1_RT0_2A")
		)
		(pad "2" smd rect
			(at -0.2667 0 270)
			(size 0.3048 0.381)
			(layers "B.Cu" "B.Mask" "B.Paste")
			(net "GND")
		)
	)
	(footprint ""
		(layer "B.Cu")
		(at 82.446368 -388.011162 -90)
		(property "Reference" "C319"
			(at 0 0 90)
			(layer "B.SilkS")
			(hide yes)
			(effects
				(font
					(size 1.27 1.27)
				)
				(justify mirror)
			)
		)
		(property "Value" ""
			(at 0 0 90)
			(layer "B.Fab")
			(effects
				(font
					(size 1.27 1.27)
				)
				(justify mirror)
			)
		)
		(duplicate_pad_numbers_are_jumpers no)
		(fp_line
			(start -0.299974 0.150114)
			(end 0.299974 0.150114)
			(stroke
				(width 0.1)
				(type default)
			)
			(layer "B.Fab")
		)
		(fp_line
			(start 0.299974 0.150114)
			(end 0.299974 -0.150114)
			(stroke
				(width 0.1)
				(type default)
			)
			(layer "B.Fab")
		)
		(fp_line
			(start -0.299974 -0.150114)
			(end -0.299974 0.150114)
			(stroke
				(width 0.1)
				(type default)
			)
			(layer "B.Fab")
		)
		(fp_line
			(start 0.299974 -0.150114)
			(end -0.299974 -0.150114)
			(stroke
				(width 0.1)
				(type default)
			)
			(layer "B.Fab")
		)
		(pad "1" smd rect
			(at 0.2667 0 90)
			(size 0.3048 0.381)
			(layers "B.Cu" "B.Mask" "B.Paste")
			(net "P0V9_CPU1_RT1_2A")
		)
		(pad "2" smd rect
			(at -0.2667 0 90)
			(size 0.3048 0.381)
			(layers "B.Cu" "B.Mask" "B.Paste")
			(net "GND")
		)
	)
)
